#ISCELL
  mstr_symbols cad_note *
  *
#ISCELL
  mstr_symbols design_note *
  *
#ISCELL
  mstr_symbols intel_corp_bpage *
  *
#ISCELL
  mstr_standard offpage *
  page160_i1
#ISCELL
  mstr_standard offpage *
  page160_i10
#ISCELL
  mstr_standard offpage *
  page160_i17
#ISCELL
  mstr_standard offpage *
  page160_i18
#ISCELL
  mstr_standard offpage *
  page160_i19
#ISCELL
  mstr_standard offpage *
  page160_i2
#ISCELL
  mstr_standard offpage *
  page160_i20
#CELL
  mstr_discrete res *
  page160_i4
#CELL
  mstr_discrete res *
  page160_i46
#ISCELL
  mstr_symbols p3v3_stby *
  page160_i47
#ISCELL
  mstr_symbols p3v3_stby *
  page160_i48
#CELL
  mstr_discrete res *
  page160_i49
#CELL
  mstr_discrete res *
  page160_i50
#CELL
  mstr_discrete res *
  page160_i51
#CELL
  mstr_discrete res *
  page160_i52
#ISCELL
  mstr_standard offpage *
  page160_i9
